(kicad_pcb
	(version 20260206)
	(generator "pcbnew")
	(generator_version "10.0")
	(general
		(thickness 1.6)
		(legacy_teardrops no)
	)
	(paper "A4")
	(title_block
		(title "01162023_DA0F0TEBIF0_F0T_Expander_BD_F_brd_V02_OCP.brd")
		(comment 1 "Grand Teton / footprints 1009-1014 of 9728")
	)
	(layers
		(0 "F.Cu" signal "TOP")
		(4 "In1.Cu" signal "GND")
		(6 "In2.Cu" signal "VCC")
		(8 "In3.Cu" signal "VCC1")
		(10 "In4.Cu" signal "GND1")
		(12 "In5.Cu" signal "IN1")
		(14 "In6.Cu" signal "GND2")
		(16 "In7.Cu" signal "IN2")
		(18 "In8.Cu" signal "GND3")
		(20 "In9.Cu" signal "IN3")
		(22 "In10.Cu" signal "GND4")
		(24 "In11.Cu" signal "IN4")
		(26 "In12.Cu" signal "GND5")
		(28 "In13.Cu" signal "IN5")
		(30 "In14.Cu" signal "GND6")
		(32 "In15.Cu" signal "IN6")
		(34 "In16.Cu" signal "GND7")
		(2 "B.Cu" signal "BOTTOM")
		(9 "F.Adhes" user "F.Adhesive")
		(11 "B.Adhes" user "B.Adhesive")
		(13 "F.Paste" user "Package Geometry/Pastemask Top")
		(15 "B.Paste" user "Package Geometry/Pastemask Bottom")
		(5 "F.SilkS" user "Ref Des/Silkscreen Top")
		(7 "B.SilkS" user "Ref Des/Silkscreen Bottom")
		(1 "F.Mask" user "Board Geometry/Soldermask Top")
		(3 "B.Mask" user "Board Geometry/Soldermask Bottom")
		(17 "Dwgs.User" user "User.Drawings")
		(19 "Cmts.User" user "User.Comments")
		(21 "Eco1.User" user "User.Eco1")
		(23 "Eco2.User" user "User.Eco2")
		(25 "Edge.Cuts" user "Board Geometry/Outline")
		(27 "Margin" user)
		(31 "F.CrtYd" user "Package Geometry/Place Bound Top")
		(29 "B.CrtYd" user "Package Geometry/Place Bound Bottom")
		(35 "F.Fab" user "Ref Des/Assembly Top")
		(33 "B.Fab" user "Ref Des/Assembly Bottom")
	)
	(footprint ""
		(layer "F.Cu")
		(at 359.156 -190.246 180)
		(property "Reference" "R4613"
			(at 0 0 180)
			(layer "F.SilkS")
			(hide yes)
			(effects
				(font
					(size 1.27 1.27)
				)
			)
		)
		(property "Value" ""
			(at 0 0 180)
			(layer "F.Fab")
			(effects
				(font
					(size 1.27 1.27)
				)
			)
		)
		(duplicate_pad_numbers_are_jumpers no)
		(fp_line
			(start 0.7874 0.4064)
			(end -0.7874 0.4064)
			(stroke
				(width 0.1524)
				(type default)
			)
			(layer "F.SilkS")
		)
		(fp_line
			(start 0.7874 -0.4064)
			(end 0.7874 0.4064)
			(stroke
				(width 0.1524)
				(type default)
			)
			(layer "F.SilkS")
		)
		(fp_line
			(start -0.7874 0.4064)
			(end -0.7874 -0.4064)
			(stroke
				(width 0.1524)
				(type default)
			)
			(layer "F.SilkS")
		)
		(fp_line
			(start -0.7874 -0.4064)
			(end 0.7874 -0.4064)
			(stroke
				(width 0.1524)
				(type default)
			)
			(layer "F.SilkS")
		)
		(fp_line
			(start 0.67945 0.3048)
			(end 0.120396 0.3048)
			(stroke
				(width 0.1)
				(type default)
			)
			(layer "F.Fab")
		)
		(fp_line
			(start 0.67945 -0.3048)
			(end 0.67945 0.3048)
			(stroke
				(width 0.1)
				(type default)
			)
			(layer "F.Fab")
		)
		(fp_line
			(start 0.12065 -0.2794)
			(end 0.12065 -0.3048)
			(stroke
				(width 0.1)
				(type default)
			)
			(layer "F.Fab")
		)
		(fp_line
			(start 0.12065 -0.3048)
			(end 0.67945 -0.3048)
			(stroke
				(width 0.1)
				(type default)
			)
			(layer "F.Fab")
		)
		(fp_line
			(start 0.120396 0.3048)
			(end 0.120396 0.2794)
			(stroke
				(width 0.1)
				(type default)
			)
			(layer "F.Fab")
		)
		(fp_line
			(start 0.120396 0.2794)
			(end -0.12065 0.2794)
			(stroke
				(width 0.1)
				(type default)
			)
			(layer "F.Fab")
		)
		(fp_line
			(start -0.12065 0.3048)
			(end -0.67945 0.3048)
			(stroke
				(width 0.1)
				(type default)
			)
			(layer "F.Fab")
		)
		(fp_line
			(start -0.12065 0.2794)
			(end -0.12065 0.3048)
			(stroke
				(width 0.1)
				(type default)
			)
			(layer "F.Fab")
		)
		(fp_line
			(start -0.12065 -0.2794)
			(end 0.12065 -0.2794)
			(stroke
				(width 0.1)
				(type default)
			)
			(layer "F.Fab")
		)
		(fp_line
			(start -0.12065 -0.305054)
			(end -0.12065 -0.2794)
			(stroke
				(width 0.1)
				(type default)
			)
			(layer "F.Fab")
		)
		(fp_line
			(start -0.67945 0.3048)
			(end -0.67945 -0.305054)
			(stroke
				(width 0.1)
				(type default)
			)
			(layer "F.Fab")
		)
		(fp_line
			(start -0.67945 -0.305054)
			(end -0.12065 -0.305054)
			(stroke
				(width 0.1)
				(type default)
			)
			(layer "F.Fab")
		)
		(pad "1" smd circle
			(at -0.40005 0 180)
			(size 0 0)
			(layers "F.Cu" "F.Mask" "F.Paste")
			(net "SSD2_PEX_PWR_EN_R")
		)
		(pad "2" smd circle
			(at 0.40005 0 180)
			(size 0 0)
			(layers "F.Cu" "F.Mask" "F.Paste")
			(net "GND")
		)
	)
	(footprint ""
		(layer "F.Cu")
		(at 378.382022 -296.191432 180)
		(property "Reference" "C3552"
			(at 0 0 180)
			(layer "F.SilkS")
			(hide yes)
			(effects
				(font
					(size 1.27 1.27)
				)
			)
		)
		(property "Value" ""
			(at 0 0 180)
			(layer "F.Fab")
			(effects
				(font
					(size 1.27 1.27)
				)
			)
		)
		(duplicate_pad_numbers_are_jumpers no)
		(fp_line
			(start 1.2954 0.5842)
			(end -1.2954 0.5842)
			(stroke
				(width 0.1524)
				(type default)
			)
			(layer "F.SilkS")
		)
		(fp_line
			(start 1.2954 -0.5842)
			(end 1.2954 0.5842)
			(stroke
				(width 0.1524)
				(type default)
			)
			(layer "F.SilkS")
		)
		(fp_line
			(start -1.2954 0.5842)
			(end -1.2954 -0.5842)
			(stroke
				(width 0.1524)
				(type default)
			)
			(layer "F.SilkS")
		)
		(fp_line
			(start -1.2954 -0.5842)
			(end 1.2954 -0.5842)
			(stroke
				(width 0.1524)
				(type default)
			)
			(layer "F.SilkS")
		)
		(fp_line
			(start 1.1938 0.4064)
			(end 0.8636 0.4064)
			(stroke
				(width 0.1)
				(type default)
			)
			(layer "F.Fab")
		)
		(fp_line
			(start 1.1938 -0.4064)
			(end 1.1938 0.4064)
			(stroke
				(width 0.1)
				(type default)
			)
			(layer "F.Fab")
		)
		(fp_line
			(start 0.8636 0.4572)
			(end -0.8636 0.4572)
			(stroke
				(width 0.1)
				(type default)
			)
			(layer "F.Fab")
		)
		(fp_line
			(start 0.8636 0.4064)
			(end 0.8636 0.4572)
			(stroke
				(width 0.1)
				(type default)
			)
			(layer "F.Fab")
		)
		(fp_line
			(start 0.8636 -0.4064)
			(end 1.1938 -0.4064)
			(stroke
				(width 0.1)
				(type default)
			)
			(layer "F.Fab")
		)
		(fp_line
			(start 0.8636 -0.4572)
			(end 0.8636 -0.4064)
			(stroke
				(width 0.1)
				(type default)
			)
			(layer "F.Fab")
		)
		(fp_line
			(start -0.8636 0.4572)
			(end -0.8636 0.4064)
			(stroke
				(width 0.1)
				(type default)
			)
			(layer "F.Fab")
		)
		(fp_line
			(start -0.8636 0.4064)
			(end -1.1938 0.4064)
			(stroke
				(width 0.1)
				(type default)
			)
			(layer "F.Fab")
		)
		(fp_line
			(start -0.8636 -0.4064)
			(end -0.8636 -0.4572)
			(stroke
				(width 0.1)
				(type default)
			)
			(layer "F.Fab")
		)
		(fp_line
			(start -0.8636 -0.4572)
			(end 0.8636 -0.4572)
			(stroke
				(width 0.1)
				(type default)
			)
			(layer "F.Fab")
		)
		(fp_line
			(start -1.1938 0.4064)
			(end -1.1938 -0.4064)
			(stroke
				(width 0.1)
				(type default)
			)
			(layer "F.Fab")
		)
		(fp_line
			(start -1.1938 -0.4064)
			(end -0.8636 -0.4064)
			(stroke
				(width 0.1)
				(type default)
			)
			(layer "F.Fab")
		)
		(pad "1" smd rect
			(at -0.7366 0 90)
			(size 0.7112 0.8128)
			(layers "F.Cu" "F.Mask" "F.Paste")
			(net "PCEPLL0_VDDA18_PEX3_R")
		)
		(pad "2" smd rect
			(at 0.7366 0 90)
			(size 0.7112 0.8128)
			(layers "F.Cu" "F.Mask" "F.Paste")
			(net "GND")
		)
	)
	(footprint ""
		(layer "F.Cu")
		(at 7.189216 -15.119858 180)
		(property "Reference" "C3872"
			(at 0 0 180)
			(layer "F.SilkS")
			(hide yes)
			(effects
				(font
					(size 1.27 1.27)
				)
			)
		)
		(property "Value" ""
			(at 0 0 180)
			(layer "F.Fab")
			(effects
				(font
					(size 1.27 1.27)
				)
			)
		)
		(duplicate_pad_numbers_are_jumpers no)
		(fp_line
			(start 0.7874 0.4064)
			(end -0.7874 0.4064)
			(stroke
				(width 0.1524)
				(type default)
			)
			(layer "F.SilkS")
		)
		(fp_line
			(start 0.7874 -0.4064)
			(end 0.7874 0.4064)
			(stroke
				(width 0.1524)
				(type default)
			)
			(layer "F.SilkS")
		)
		(fp_line
			(start -0.7874 0.4064)
			(end -0.7874 -0.4064)
			(stroke
				(width 0.1524)
				(type default)
			)
			(layer "F.SilkS")
		)
		(fp_line
			(start -0.7874 -0.4064)
			(end 0.7874 -0.4064)
			(stroke
				(width 0.1524)
				(type default)
			)
			(layer "F.SilkS")
		)
		(fp_line
			(start 0.67945 0.3048)
			(end 0.120396 0.3048)
			(stroke
				(width 0.1)
				(type default)
			)
			(layer "F.Fab")
		)
		(fp_line
			(start 0.67945 -0.3048)
			(end 0.67945 0.3048)
			(stroke
				(width 0.1)
				(type default)
			)
			(layer "F.Fab")
		)
		(fp_line
			(start 0.12065 -0.2794)
			(end 0.12065 -0.3048)
			(stroke
				(width 0.1)
				(type default)
			)
			(layer "F.Fab")
		)
		(fp_line
			(start 0.12065 -0.3048)
			(end 0.67945 -0.3048)
			(stroke
				(width 0.1)
				(type default)
			)
			(layer "F.Fab")
		)
		(fp_line
			(start 0.120396 0.3048)
			(end 0.120396 0.2794)
			(stroke
				(width 0.1)
				(type default)
			)
			(layer "F.Fab")
		)
		(fp_line
			(start 0.120396 0.2794)
			(end -0.12065 0.2794)
			(stroke
				(width 0.1)
				(type default)
			)
			(layer "F.Fab")
		)
		(fp_line
			(start -0.12065 0.3048)
			(end -0.67945 0.3048)
			(stroke
				(width 0.1)
				(type default)
			)
			(layer "F.Fab")
		)
		(fp_line
			(start -0.12065 0.2794)
			(end -0.12065 0.3048)
			(stroke
				(width 0.1)
				(type default)
			)
			(layer "F.Fab")
		)
		(fp_line
			(start -0.12065 -0.2794)
			(end 0.12065 -0.2794)
			(stroke
				(width 0.1)
				(type default)
			)
			(layer "F.Fab")
		)
		(fp_line
			(start -0.12065 -0.305054)
			(end -0.12065 -0.2794)
			(stroke
				(width 0.1)
				(type default)
			)
			(layer "F.Fab")
		)
		(fp_line
			(start -0.67945 0.3048)
			(end -0.67945 -0.305054)
			(stroke
				(width 0.1)
				(type default)
			)
			(layer "F.Fab")
		)
		(fp_line
			(start -0.67945 -0.305054)
			(end -0.12065 -0.305054)
			(stroke
				(width 0.1)
				(type default)
			)
			(layer "F.Fab")
		)
		(pad "1" smd circle
			(at -0.40005 0 180)
			(size 0 0)
			(layers "F.Cu" "F.Mask" "F.Paste")
			(net "P12V_SSD0")
		)
		(pad "2" smd circle
			(at 0.40005 0 180)
			(size 0 0)
			(layers "F.Cu" "F.Mask" "F.Paste")
			(net "GND")
		)
	)
	(footprint ""
		(layer "F.Cu")
		(at 186.822588 -44.341542 90)
		(property "Reference" "R580"
			(at 0 0 90)
			(layer "F.SilkS")
			(hide yes)
			(effects
				(font
					(size 1.27 1.27)
				)
			)
		)
		(property "Value" ""
			(at 0 0 90)
			(layer "F.Fab")
			(effects
				(font
					(size 1.27 1.27)
				)
			)
		)
		(duplicate_pad_numbers_are_jumpers no)
		(fp_line
			(start 0.7874 -0.4064)
			(end 0.7874 0.4064)
			(stroke
				(width 0.1524)
				(type default)
			)
			(layer "F.SilkS")
		)
		(fp_line
			(start -0.7874 -0.4064)
			(end 0.7874 -0.4064)
			(stroke
				(width 0.1524)
				(type default)
			)
			(layer "F.SilkS")
		)
		(fp_line
			(start 0.7874 0.4064)
			(end -0.7874 0.4064)
			(stroke
				(width 0.1524)
				(type default)
			)
			(layer "F.SilkS")
		)
		(fp_line
			(start -0.7874 0.4064)
			(end -0.7874 -0.4064)
			(stroke
				(width 0.1524)
				(type default)
			)
			(layer "F.SilkS")
		)
		(fp_line
			(start -0.12065 -0.305054)
			(end -0.12065 -0.2794)
			(stroke
				(width 0.1)
				(type default)
			)
			(layer "F.Fab")
		)
		(fp_line
			(start -0.67945 -0.305054)
			(end -0.12065 -0.305054)
			(stroke
				(width 0.1)
				(type default)
			)
			(layer "F.Fab")
		)
		(fp_line
			(start 0.67945 -0.3048)
			(end 0.67945 0.3048)
			(stroke
				(width 0.1)
				(type default)
			)
			(layer "F.Fab")
		)
		(fp_line
			(start 0.12065 -0.3048)
			(end 0.67945 -0.3048)
			(stroke
				(width 0.1)
				(type default)
			)
			(layer "F.Fab")
		)
		(fp_line
			(start 0.12065 -0.2794)
			(end 0.12065 -0.3048)
			(stroke
				(width 0.1)
				(type default)
			)
			(layer "F.Fab")
		)
		(fp_line
			(start -0.12065 -0.2794)
			(end 0.12065 -0.2794)
			(stroke
				(width 0.1)
				(type default)
			)
			(layer "F.Fab")
		)
		(fp_line
			(start 0.120396 0.2794)
			(end -0.12065 0.2794)
			(stroke
				(width 0.1)
				(type default)
			)
			(layer "F.Fab")
		)
		(fp_line
			(start -0.12065 0.2794)
			(end -0.12065 0.3048)
			(stroke
				(width 0.1)
				(type default)
			)
			(layer "F.Fab")
		)
		(fp_line
			(start 0.67945 0.3048)
			(end 0.120396 0.3048)
			(stroke
				(width 0.1)
				(type default)
			)
			(layer "F.Fab")
		)
		(fp_line
			(start 0.120396 0.3048)
			(end 0.120396 0.2794)
			(stroke
				(width 0.1)
				(type default)
			)
			(layer "F.Fab")
		)
		(fp_line
			(start -0.12065 0.3048)
			(end -0.67945 0.3048)
			(stroke
				(width 0.1)
				(type default)
			)
			(layer "F.Fab")
		)
		(fp_line
			(start -0.67945 0.3048)
			(end -0.67945 -0.305054)
			(stroke
				(width 0.1)
				(type default)
			)
			(layer "F.Fab")
		)
		(pad "1" smd circle
			(at -0.40005 0 90)
			(size 0 0)
			(layers "F.Cu" "F.Mask" "F.Paste")
			(net "P12V_SSD6")
		)
		(pad "2" smd circle
			(at 0.40005 0 90)
			(size 0 0)
			(layers "F.Cu" "F.Mask" "F.Paste")
			(net "P12V_SSD6_VIN_N")
		)
	)
	(footprint ""
		(layer "F.Cu")
		(at 21.872956 -173.255178)
		(property "Reference" "PR58"
			(at 0 0 0)
			(layer "F.SilkS")
			(hide yes)
			(effects
				(font
					(size 1.27 1.27)
				)
			)
		)
		(property "Value" ""
			(at 0 0 0)
			(layer "F.Fab")
			(effects
				(font
					(size 1.27 1.27)
				)
			)
		)
		(duplicate_pad_numbers_are_jumpers no)
		(fp_line
			(start -0.7874 -0.4064)
			(end 0.7874 -0.4064)
			(stroke
				(width 0.1524)
				(type default)
			)
			(layer "F.SilkS")
		)
		(fp_line
			(start -0.7874 0.4064)
			(end -0.7874 -0.4064)
			(stroke
				(width 0.1524)
				(type default)
			)
			(layer "F.SilkS")
		)
		(fp_line
			(start 0.7874 -0.4064)
			(end 0.7874 0.4064)
			(stroke
				(width 0.1524)
				(type default)
			)
			(layer "F.SilkS")
		)
		(fp_line
			(start 0.7874 0.4064)
			(end -0.7874 0.4064)
			(stroke
				(width 0.1524)
				(type default)
			)
			(layer "F.SilkS")
		)
		(fp_line
			(start -0.67945 -0.305054)
			(end -0.12065 -0.305054)
			(stroke
				(width 0.1)
				(type default)
			)
			(layer "F.Fab")
		)
		(fp_line
			(start -0.67945 0.3048)
			(end -0.67945 -0.305054)
			(stroke
				(width 0.1)
				(type default)
			)
			(layer "F.Fab")
		)
		(fp_line
			(start -0.12065 -0.305054)
			(end -0.12065 -0.2794)
			(stroke
				(width 0.1)
				(type default)
			)
			(layer "F.Fab")
		)
		(fp_line
			(start -0.12065 -0.2794)
			(end 0.12065 -0.2794)
			(stroke
				(width 0.1)
				(type default)
			)
			(layer "F.Fab")
		)
		(fp_line
			(start -0.12065 0.2794)
			(end -0.12065 0.3048)
			(stroke
				(width 0.1)
				(type default)
			)
			(layer "F.Fab")
		)
		(fp_line
			(start -0.12065 0.3048)
			(end -0.67945 0.3048)
			(stroke
				(width 0.1)
				(type default)
			)
			(layer "F.Fab")
		)
		(fp_line
			(start 0.120396 0.2794)
			(end -0.12065 0.2794)
			(stroke
				(width 0.1)
				(type default)
			)
			(layer "F.Fab")
		)
		(fp_line
			(start 0.120396 0.3048)
			(end 0.120396 0.2794)
			(stroke
				(width 0.1)
				(type default)
			)
			(layer "F.Fab")
		)
		(fp_line
			(start 0.12065 -0.3048)
			(end 0.67945 -0.3048)
			(stroke
				(width 0.1)
				(type default)
			)
			(layer "F.Fab")
		)
		(fp_line
			(start 0.12065 -0.2794)
			(end 0.12065 -0.3048)
			(stroke
				(width 0.1)
				(type default)
			)
			(layer "F.Fab")
		)
		(fp_line
			(start 0.67945 -0.3048)
			(end 0.67945 0.3048)
			(stroke
				(width 0.1)
				(type default)
			)
			(layer "F.Fab")
		)
		(fp_line
			(start 0.67945 0.3048)
			(end 0.120396 0.3048)
			(stroke
				(width 0.1)
				(type default)
			)
			(layer "F.Fab")
		)
		(pad "1" smd circle
			(at -0.40005 0)
			(size 0 0)
			(layers "F.Cu" "F.Mask" "F.Paste")
			(net "P5V_AUX_FB")
		)
		(pad "2" smd circle
			(at 0.40005 0)
			(size 0 0)
			(layers "F.Cu" "F.Mask" "F.Paste")
			(net "GND")
		)
	)
	(footprint ""
		(layer "F.Cu")
		(at 112.583976 -277.644352)
		(property "Reference" "PC80"
			(at 0 0 0)
			(layer "F.SilkS")
			(hide yes)
			(effects
				(font
					(size 1.27 1.27)
				)
			)
		)
		(property "Value" ""
			(at 0 0 0)
			(layer "F.Fab")
			(effects
				(font
					(size 1.27 1.27)
				)
			)
		)
		(duplicate_pad_numbers_are_jumpers no)
		(fp_line
			(start -1.524 -0.762)
			(end 1.524 -0.762)
			(stroke
				(width 0.1524)
				(type default)
			)
			(layer "F.SilkS")
		)
		(fp_line
			(start -1.524 0.762)
			(end -1.524 -0.762)
			(stroke
				(width 0.1524)
				(type default)
			)
			(layer "F.SilkS")
		)
		(fp_line
			(start 1.524 -0.762)
			(end 1.524 0.762)
			(stroke
				(width 0.1524)
				(type default)
			)
			(layer "F.SilkS")
		)
		(fp_line
			(start 1.524 0.762)
			(end -1.524 0.762)
			(stroke
				(width 0.1524)
				(type default)
			)
			(layer "F.SilkS")
		)
		(fp_line
			(start -1.1049 -0.724916)
			(end -1.1049 0.724916)
			(stroke
				(width 0.1)
				(type default)
			)
			(layer "F.Fab")
		)
		(fp_line
			(start -1.1049 0.724916)
			(end 1.1049 0.724916)
			(stroke
				(width 0.1)
				(type default)
			)
			(layer "F.Fab")
		)
		(fp_line
			(start 1.1049 -0.724916)
			(end -1.1049 -0.724916)
			(stroke
				(width 0.1)
				(type default)
			)
			(layer "F.Fab")
		)
		(fp_line
			(start 1.1049 0.724916)
			(end 1.1049 -0.724916)
			(stroke
				(width 0.1)
				(type default)
			)
			(layer "F.Fab")
		)
		(pad "1" smd rect
			(at -0.889 0 180)
			(size 1.016 1.27)
			(layers "F.Cu" "F.Mask" "F.Paste")
			(net "SW_P12V_P0V8_PEX0_FLT")
		)
		(pad "2" smd rect
			(at 0.889 0 180)
			(size 1.016 1.27)
			(layers "F.Cu" "F.Mask" "F.Paste")
			(net "GND")
		)
	)
)
